(kicad_pcb
	(version 20260206)
	(generator "pcbnew")
	(generator_version "10.0")
	(general
		(thickness 1.6)
		(legacy_teardrops no)
	)
	(paper "A4")
	(title_block
		(title "Wiwynn_Tioga_Pass_MB.brd")
		(comment 1 "Tioga Pass / footprints 1460-1464 of 4770")
	)
	(layers
		(0 "F.Cu" signal "TOP")
		(4 "In1.Cu" signal "L2GND")
		(6 "In2.Cu" signal "L3")
		(8 "In3.Cu" signal "L4GND")
		(10 "In4.Cu" signal "L5")
		(12 "In5.Cu" signal "L6GND")
		(14 "In6.Cu" signal "L7VCC")
		(16 "In7.Cu" signal "L8VCC")
		(18 "In8.Cu" signal "L9GND")
		(20 "In9.Cu" signal "L10")
		(22 "In10.Cu" signal "L11GND")
		(24 "In11.Cu" signal "L12")
		(26 "In12.Cu" signal "L13GND")
		(2 "B.Cu" signal "BOTTOM")
		(9 "F.Adhes" user "F.Adhesive")
		(11 "B.Adhes" user "B.Adhesive")
		(13 "F.Paste" user "Package Geometry/Pastemask Top")
		(15 "B.Paste" user "Package Geometry/Pastemask Bottom")
		(5 "F.SilkS" user "Ref Des/Silkscreen Top")
		(7 "B.SilkS" user "Ref Des/Silkscreen Bottom")
		(1 "F.Mask" user "Board Geometry/Soldermask Top")
		(3 "B.Mask" user "Board Geometry/Soldermask Bottom")
		(17 "Dwgs.User" user "User.Drawings")
		(19 "Cmts.User" user "User.Comments")
		(21 "Eco1.User" user "User.Eco1")
		(23 "Eco2.User" user "User.Eco2")
		(25 "Edge.Cuts" user "Board Geometry/Outline")
		(27 "Margin" user)
		(31 "F.CrtYd" user "Package Geometry/Place Bound Top")
		(29 "B.CrtYd" user "Package Geometry/Place Bound Bottom")
		(35 "F.Fab" user "Ref Des/Assembly Top")
		(33 "B.Fab" user "Ref Des/Assembly Bottom")
	)
	(footprint ""
		(layer "F.Cu")
		(at 262.133334 -83.84159)
		(property "Reference" "C5D10"
			(at 0 0 0)
			(layer "F.SilkS")
			(hide yes)
			(effects
				(font
					(size 1.27 1.27)
				)
			)
		)
		(property "Value" ""
			(at 0 0 0)
			(layer "F.Fab")
			(effects
				(font
					(size 1.27 1.27)
				)
			)
		)
		(duplicate_pad_numbers_are_jumpers no)
		(fp_poly
			(pts
				(xy -0.4953 -0.2032) (xy 0.4953 -0.2032) (xy 0.4953 1.6002) (xy -0.4953 1.6002)
			)
			(stroke
				(width 0)
				(type default)
			)
			(fill no)
			(layer "F.CrtYd")
		)
		(fp_line
			(start -0.4953 -0.2032)
			(end 0.4953 -0.2032)
			(stroke
				(width 0.1)
				(type default)
			)
			(layer "F.Fab")
		)
		(fp_line
			(start -0.4953 1.6002)
			(end -0.4953 -0.2032)
			(stroke
				(width 0.1)
				(type default)
			)
			(layer "F.Fab")
		)
		(fp_line
			(start 0.4953 -0.2032)
			(end 0.4953 1.6002)
			(stroke
				(width 0.1)
				(type default)
			)
			(layer "F.Fab")
		)
		(fp_line
			(start 0.4953 1.6002)
			(end -0.4953 1.6002)
			(stroke
				(width 0.1)
				(type default)
			)
			(layer "F.Fab")
		)
		(pad "1" smd rect
			(at 0 0)
			(size 0.762 0.889)
			(layers "F.Cu" "F.Mask" "F.Paste")
			(net "PVSA_CPU0")
		)
		(pad "2" smd rect
			(at 0 1.397)
			(size 0.762 0.889)
			(layers "F.Cu" "F.Mask" "F.Paste")
			(net "GND")
		)
		(zone
			(layer "F.Cu")
			(hatch none 0.5)
			(connect_pads
				(clearance 0)
			)
			(min_thickness 0.25)
			(keepout
				(tracks not_allowed)
				(vias allowed)
				(pads allowed)
				(copperpour not_allowed)
				(footprints allowed)
			)
			(placement
				(enabled no)
				(sheetname "")
			)
			(fill
				(thermal_gap 0.5)
				(thermal_bridge_width 0.5)
				(island_removal_mode 0)
			)
			(polygon
				(pts
					(xy 261.752334 -83.39709) (xy 262.514334 -83.39709) (xy 262.514334 -82.88909) (xy 261.752334 -82.88909)
				)
			)
		)
	)
	(footprint ""
		(layer "F.Cu")
		(at 268.165072 -77.636116)
		(property "Reference" "C5D32"
			(at 0 0 0)
			(layer "F.SilkS")
			(hide yes)
			(effects
				(font
					(size 1.27 1.27)
				)
			)
		)
		(property "Value" ""
			(at 0 0 0)
			(layer "F.Fab")
			(effects
				(font
					(size 1.27 1.27)
				)
			)
		)
		(duplicate_pad_numbers_are_jumpers no)
		(fp_poly
			(pts
				(xy -0.4953 -0.2032) (xy 0.4953 -0.2032) (xy 0.4953 1.6002) (xy -0.4953 1.6002)
			)
			(stroke
				(width 0)
				(type default)
			)
			(fill no)
			(layer "F.CrtYd")
		)
		(fp_line
			(start -0.4953 -0.2032)
			(end 0.4953 -0.2032)
			(stroke
				(width 0.1)
				(type default)
			)
			(layer "F.Fab")
		)
		(fp_line
			(start -0.4953 1.6002)
			(end -0.4953 -0.2032)
			(stroke
				(width 0.1)
				(type default)
			)
			(layer "F.Fab")
		)
		(fp_line
			(start 0.4953 -0.2032)
			(end 0.4953 1.6002)
			(stroke
				(width 0.1)
				(type default)
			)
			(layer "F.Fab")
		)
		(fp_line
			(start 0.4953 1.6002)
			(end -0.4953 1.6002)
			(stroke
				(width 0.1)
				(type default)
			)
			(layer "F.Fab")
		)
		(pad "1" smd rect
			(at 0 0)
			(size 0.762 0.889)
			(layers "F.Cu" "F.Mask" "F.Paste")
			(net "PVCCIN_CPU0")
		)
		(pad "2" smd rect
			(at 0 1.397)
			(size 0.762 0.889)
			(layers "F.Cu" "F.Mask" "F.Paste")
			(net "GND")
		)
		(zone
			(layer "F.Cu")
			(hatch none 0.5)
			(connect_pads
				(clearance 0)
			)
			(min_thickness 0.25)
			(keepout
				(tracks not_allowed)
				(vias allowed)
				(pads allowed)
				(copperpour not_allowed)
				(footprints allowed)
			)
			(placement
				(enabled no)
				(sheetname "")
			)
			(fill
				(thermal_gap 0.5)
				(thermal_bridge_width 0.5)
				(island_removal_mode 0)
			)
			(polygon
				(pts
					(xy 267.784072 -77.191616) (xy 268.546072 -77.191616) (xy 268.546072 -76.683616) (xy 267.784072 -76.683616)
				)
			)
		)
	)
	(footprint ""
		(layer "F.Cu")
		(at 266.920472 -73.318116)
		(property "Reference" "C5D46"
			(at 0 0 0)
			(layer "F.SilkS")
			(hide yes)
			(effects
				(font
					(size 1.27 1.27)
				)
			)
		)
		(property "Value" ""
			(at 0 0 0)
			(layer "F.Fab")
			(effects
				(font
					(size 1.27 1.27)
				)
			)
		)
		(duplicate_pad_numbers_are_jumpers no)
		(fp_poly
			(pts
				(xy -0.4953 -0.2032) (xy 0.4953 -0.2032) (xy 0.4953 1.6002) (xy -0.4953 1.6002)
			)
			(stroke
				(width 0)
				(type default)
			)
			(fill no)
			(layer "F.CrtYd")
		)
		(fp_line
			(start -0.4953 -0.2032)
			(end 0.4953 -0.2032)
			(stroke
				(width 0.1)
				(type default)
			)
			(layer "F.Fab")
		)
		(fp_line
			(start -0.4953 1.6002)
			(end -0.4953 -0.2032)
			(stroke
				(width 0.1)
				(type default)
			)
			(layer "F.Fab")
		)
		(fp_line
			(start 0.4953 -0.2032)
			(end 0.4953 1.6002)
			(stroke
				(width 0.1)
				(type default)
			)
			(layer "F.Fab")
		)
		(fp_line
			(start 0.4953 1.6002)
			(end -0.4953 1.6002)
			(stroke
				(width 0.1)
				(type default)
			)
			(layer "F.Fab")
		)
		(pad "1" smd rect
			(at 0 0)
			(size 0.762 0.889)
			(layers "F.Cu" "F.Mask" "F.Paste")
			(net "PVCCIN_CPU0")
		)
		(pad "2" smd rect
			(at 0 1.397)
			(size 0.762 0.889)
			(layers "F.Cu" "F.Mask" "F.Paste")
			(net "GND")
		)
		(zone
			(layer "F.Cu")
			(hatch none 0.5)
			(connect_pads
				(clearance 0)
			)
			(min_thickness 0.25)
			(keepout
				(tracks not_allowed)
				(vias allowed)
				(pads allowed)
				(copperpour not_allowed)
				(footprints allowed)
			)
			(placement
				(enabled no)
				(sheetname "")
			)
			(fill
				(thermal_gap 0.5)
				(thermal_bridge_width 0.5)
				(island_removal_mode 0)
			)
			(polygon
				(pts
					(xy 266.539472 -72.873616) (xy 267.301472 -72.873616) (xy 267.301472 -72.365616) (xy 266.539472 -72.365616)
				)
			)
		)
	)
	(footprint ""
		(layer "F.Cu")
		(at 13.8938 -32.131 90)
		(property "Reference" "C1F8"
			(at 0 0 90)
			(layer "F.SilkS")
			(hide yes)
			(effects
				(font
					(size 1.27 1.27)
				)
			)
		)
		(property "Value" ""
			(at 0 0 90)
			(layer "F.Fab")
			(effects
				(font
					(size 1.27 1.27)
				)
			)
		)
		(duplicate_pad_numbers_are_jumpers no)
		(fp_rect
			(start -0.3048 -0.1016)
			(end 0.3048 0.9906)
			(stroke
				(width 0)
				(type default)
			)
			(fill no)
			(layer "F.CrtYd")
		)
		(fp_line
			(start 0.3048 -0.1016)
			(end -0.3048 -0.1016)
			(stroke
				(width 0.1)
				(type default)
			)
			(layer "F.Fab")
		)
		(fp_line
			(start -0.3048 -0.1016)
			(end -0.3048 0.9906)
			(stroke
				(width 0.1)
				(type default)
			)
			(layer "F.Fab")
		)
		(fp_line
			(start 0.3048 0.9906)
			(end 0.3048 -0.1016)
			(stroke
				(width 0.1)
				(type default)
			)
			(layer "F.Fab")
		)
		(fp_line
			(start -0.3048 0.9906)
			(end 0.3048 0.9906)
			(stroke
				(width 0.1)
				(type default)
			)
			(layer "F.Fab")
		)
		(pad "1" smd rect
			(at 0 0 90)
			(size 0.508 0.508)
			(layers "F.Cu" "F.Mask" "F.Paste")
			(net "P3E_CPU1_PE3_MP_C_TXN<5>")
		)
		(pad "2" smd rect
			(at 0 0.889 90)
			(size 0.508 0.508)
			(layers "F.Cu" "F.Mask" "F.Paste")
			(net "P3E_CPU1_PE3_MP_TXN<5>")
		)
		(zone
			(layer "F.Cu")
			(hatch none 0.5)
			(connect_pads
				(clearance 0)
			)
			(min_thickness 0.25)
			(keepout
				(tracks allowed)
				(vias not_allowed)
				(pads allowed)
				(copperpour not_allowed)
				(footprints allowed)
			)
			(placement
				(enabled no)
				(sheetname "")
			)
			(fill
				(thermal_gap 0.5)
				(thermal_bridge_width 0.5)
				(island_removal_mode 0)
			)
			(polygon
				(pts
					(xy 14.1478 -31.877) (xy 14.5288 -31.877) (xy 14.5288 -32.385) (xy 14.1478 -32.385)
				)
			)
		)
		(zone
			(layer "F.Cu")
			(hatch none 0.5)
			(connect_pads
				(clearance 0)
			)
			(min_thickness 0.25)
			(keepout
				(tracks not_allowed)
				(vias allowed)
				(pads allowed)
				(copperpour not_allowed)
				(footprints allowed)
			)
			(placement
				(enabled no)
				(sheetname "")
			)
			(fill
				(thermal_gap 0.5)
				(thermal_bridge_width 0.5)
				(island_removal_mode 0)
			)
			(polygon
				(pts
					(xy 14.1478 -31.877) (xy 14.5288 -31.877) (xy 14.5288 -32.385) (xy 14.1478 -32.385)
				)
			)
		)
	)
	(footprint ""
		(layer "F.Cu")
		(at 443.253876 -12.599924 90)
		(property "Reference" "R9G34"
			(at 0 0 90)
			(layer "F.SilkS")
			(hide yes)
			(effects
				(font
					(size 1.27 1.27)
				)
			)
		)
		(property "Value" ""
			(at 0 0 90)
			(layer "F.Fab")
			(effects
				(font
					(size 1.27 1.27)
				)
			)
		)
		(duplicate_pad_numbers_are_jumpers no)
		(fp_poly
			(pts
				(xy -0.2794 -0.1016) (xy 0.2794 -0.1016) (xy 0.2794 0.9906) (xy -0.2794 0.9906)
			)
			(stroke
				(width 0)
				(type default)
			)
			(fill no)
			(layer "F.CrtYd")
		)
		(fp_line
			(start 0.2794 -0.1016)
			(end -0.2794 -0.1016)
			(stroke
				(width 0.1)
				(type default)
			)
			(layer "F.Fab")
		)
		(fp_line
			(start -0.2794 -0.1016)
			(end -0.2794 0.9906)
			(stroke
				(width 0.1)
				(type default)
			)
			(layer "F.Fab")
		)
		(fp_line
			(start 0.2794 0.9906)
			(end 0.2794 -0.1016)
			(stroke
				(width 0.1)
				(type default)
			)
			(layer "F.Fab")
		)
		(fp_line
			(start -0.2794 0.9906)
			(end 0.2794 0.9906)
			(stroke
				(width 0.1)
				(type default)
			)
			(layer "F.Fab")
		)
		(pad "1" smd rect
			(at 0 0 90)
			(size 0.508 0.508)
			(layers "F.Cu" "F.Mask" "F.Paste")
			(net "H_CPU0_MEMABC_MEMHOT_G_N")
		)
		(pad "2" smd rect
			(at 0 0.889 90)
			(size 0.508 0.508)
			(layers "F.Cu" "F.Mask" "F.Paste")
			(net "H_CPU0_MEMABC_MEMHOT_G_R_N")
		)
		(zone
			(layer "F.Cu")
			(hatch none 0.5)
			(connect_pads
				(clearance 0)
			)
			(min_thickness 0.25)
			(keepout
				(tracks allowed)
				(vias not_allowed)
				(pads allowed)
				(copperpour not_allowed)
				(footprints allowed)
			)
			(placement
				(enabled no)
				(sheetname "")
			)
			(fill
				(thermal_gap 0.5)
				(thermal_bridge_width 0.5)
				(island_removal_mode 0)
			)
			(polygon
				(pts
					(xy 443.507876 -12.345924) (xy 443.507876 -12.853924) (xy 443.888876 -12.853924) (xy 443.888876 -12.345924)
				)
			)
		)
		(zone
			(layer "F.Cu")
			(hatch none 0.5)
			(connect_pads
				(clearance 0)
			)
			(min_thickness 0.25)
			(keepout
				(tracks not_allowed)
				(vias allowed)
				(pads allowed)
				(copperpour not_allowed)
				(footprints allowed)
			)
			(placement
				(enabled no)
				(sheetname "")
			)
			(fill
				(thermal_gap 0.5)
				(thermal_bridge_width 0.5)
				(island_removal_mode 0)
			)
			(polygon
				(pts
					(xy 443.888876 -12.345924) (xy 443.888876 -12.853924) (xy 443.507876 -12.853924) (xy 443.507876 -12.345924)
				)
			)
		)
	)
)
